(kicad_pcb
	(version 20241229)
	(generator "pcbnew")
	(generator_version "9.0")
	(general
		(thickness 1.294)
		(legacy_teardrops no)
	)
	(paper "A3")
	(title_block
		(title "Kintex 410T devboard")
		(date "2024-04-03")
		(rev "1.1.2")
		(comment 9 "footprints 142-148 of 975")
	)
	(layers
		(0 "F.Cu" mixed)
		(4 "In1.Cu" power)
		(6 "In2.Cu" power)
		(8 "In3.Cu" mixed)
		(10 "In4.Cu" power)
		(12 "In5.Cu" mixed)
		(14 "In6.Cu" power)
		(16 "In7.Cu" mixed)
		(18 "In8.Cu" power)
		(2 "B.Cu" mixed)
		(9 "F.Adhes" user "F.Adhesive")
		(11 "B.Adhes" user "B.Adhesive")
		(13 "F.Paste" user)
		(15 "B.Paste" user)
		(5 "F.SilkS" user "F.Silkscreen")
		(7 "B.SilkS" user "B.Silkscreen")
		(1 "F.Mask" user)
		(3 "B.Mask" user)
		(17 "Dwgs.User" user "User.Drawings")
		(19 "Cmts.User" user "User.Comments")
		(21 "Eco1.User" user "User.Eco1")
		(23 "Eco2.User" user "User.Eco2")
		(25 "Edge.Cuts" user)
		(27 "Margin" user)
		(31 "F.CrtYd" user "F.Courtyard")
		(29 "B.CrtYd" user "B.Courtyard")
		(35 "F.Fab" user)
		(33 "B.Fab" user)
	)
	(footprint "antmicro-footprints:C_0402_1005Metric"
		(layer "F.Cu")
		(at 192.6 165.649 90)
		(descr "Capacitor SMD 0402")
		(tags "capacitor SMD 0402")
		(property "Reference" "C364"
			(at -1.401 -0.5 90)
			(layer "F.SilkS")
			(effects
				(font
					(size 0.7 0.7)
					(thickness 0.15)
				)
				(justify left bottom)
			)
		)
		(property "Value" "C_22p_0402"
			(at 0 1.4 90)
			(layer "F.Fab")
			(effects
				(font
					(size 0.7 0.7)
					(thickness 0.15)
				)
				(justify left bottom)
			)
		)
		(property "Description" "SMD Multilayer Ceramic Capacitor, 22 pF, 50 V, 0402 [1005 Metric], ± 5%, C0G / NP0, CC Series"
			(at 0 0 90)
			(layer "F.Fab")
			(hide yes)
			(effects
				(font
					(size 1.27 1.27)
					(thickness 0.15)
				)
			)
		)
		(property "Author" "Antmicro"
			(at 358.249 -26.951 0)
			(layer "F.Fab")
			(hide yes)
			(effects
				(font
					(size 1 1)
					(thickness 0.15)
				)
			)
		)
		(property "Dielectric" ""
			(at 358.249 -26.951 0)
			(layer "F.Fab")
			(hide yes)
			(effects
				(font
					(size 1 1)
					(thickness 0.15)
				)
			)
		)
		(property "License" "Apache-2.0"
			(at 358.249 -26.951 0)
			(layer "F.Fab")
			(hide yes)
			(effects
				(font
					(size 1 1)
					(thickness 0.15)
				)
			)
		)
		(property "MPN" "CC0402JRNPO9BN220"
			(at 358.249 -26.951 0)
			(layer "F.Fab")
			(hide yes)
			(effects
				(font
					(size 1 1)
					(thickness 0.15)
				)
			)
		)
		(property "Manufacturer" "YAGEO"
			(at 358.249 -26.951 0)
			(layer "F.Fab")
			(hide yes)
			(effects
				(font
					(size 1 1)
					(thickness 0.15)
				)
			)
		)
		(property "Val" "22p"
			(at 358.249 -26.951 0)
			(layer "F.Fab")
			(hide yes)
			(effects
				(font
					(size 1 1)
					(thickness 0.15)
				)
			)
		)
		(property "Voltage" ""
			(at 358.249 -26.951 0)
			(layer "F.Fab")
			(hide yes)
			(effects
				(font
					(size 1 1)
					(thickness 0.15)
				)
			)
		)
		(sheetname "DC-DC Converters")
		(sheetfile "dc-dc.kicad_sch")
		(attr smd)
		(fp_rect
			(start -0.925 -0.47)
			(end 0.925 0.47)
			(stroke
				(width 0.05)
				(type default)
			)
			(fill no)
			(layer "F.CrtYd")
		)
		(fp_line
			(start 0.504 -0.25)
			(end 0.504 0.248)
			(stroke
				(width 0.15)
				(type solid)
			)
			(layer "F.Fab")
		)
		(fp_line
			(start -0.494 -0.25)
			(end 0.504 -0.25)
			(stroke
				(width 0.15)
				(type solid)
			)
			(layer "F.Fab")
		)
		(fp_line
			(start 0.504 0.248)
			(end -0.494 0.248)
			(stroke
				(width 0.15)
				(type solid)
			)
			(layer "F.Fab")
		)
		(fp_line
			(start -0.494 0.248)
			(end -0.494 -0.25)
			(stroke
				(width 0.15)
				(type solid)
			)
			(layer "F.Fab")
		)
		(pad "1" smd roundrect
			(at -0.48 0 90)
			(size 0.59 0.64)
			(layers "F.Cu" "F.Mask" "F.Paste")
			(roundrect_rratio 0.25)
			(net 1230 "Net-(C364-Pad1)")
			(pintype "passive")
		)
		(pad "2" smd roundrect
			(at 0.48 0 90)
			(size 0.59 0.64)
			(layers "F.Cu" "F.Mask" "F.Paste")
			(roundrect_rratio 0.25)
			(net 751 "/DC-DC Converters/1V0_REG")
			(pintype "passive")
		)
	)
	(footprint "antmicro-footprints:C_0402_1005Metric"
		(layer "F.Cu")
		(at 173.077501 131.000001 90)
		(descr "Capacitor SMD 0402")
		(tags "capacitor SMD 0402")
		(property "Reference" "C309"
			(at -3.699999 0.369999 90)
			(layer "F.SilkS")
			(effects
				(font
					(size 0.7 0.7)
					(thickness 0.15)
				)
				(justify left bottom)
			)
		)
		(property "Value" "C_100n_0402"
			(at 0 1.4 90)
			(layer "F.Fab")
			(effects
				(font
					(size 0.7 0.7)
					(thickness 0.15)
				)
				(justify left bottom)
			)
		)
		(property "Description" "SMD Multilayer Ceramic Capacitor, 0.1 µF, 50 V, 0402 [1005 Metric], ± 10%, X5R, GRM Series"
			(at 0 0 90)
			(layer "F.Fab")
			(hide yes)
			(effects
				(font
					(size 1.27 1.27)
					(thickness 0.15)
				)
			)
		)
		(property "Author" "Antmicro"
			(at 304.077502 -42.0775 0)
			(layer "F.Fab")
			(hide yes)
			(effects
				(font
					(size 1 1)
					(thickness 0.15)
				)
			)
		)
		(property "Dielectric" "X5R"
			(at 304.077502 -42.0775 0)
			(layer "F.Fab")
			(hide yes)
			(effects
				(font
					(size 1 1)
					(thickness 0.15)
				)
			)
		)
		(property "License" "Apache-2.0"
			(at 304.077502 -42.0775 0)
			(layer "F.Fab")
			(hide yes)
			(effects
				(font
					(size 1 1)
					(thickness 0.15)
				)
			)
		)
		(property "MPN" "GRM155R61H104KE14D"
			(at 304.077502 -42.0775 0)
			(layer "F.Fab")
			(hide yes)
			(effects
				(font
					(size 1 1)
					(thickness 0.15)
				)
			)
		)
		(property "Manufacturer" "Murata"
			(at 304.077502 -42.0775 0)
			(layer "F.Fab")
			(hide yes)
			(effects
				(font
					(size 1 1)
					(thickness 0.15)
				)
			)
		)
		(property "Val" "100n"
			(at 304.077502 -42.0775 0)
			(layer "F.Fab")
			(hide yes)
			(effects
				(font
					(size 1 1)
					(thickness 0.15)
				)
			)
		)
		(property "Voltage" "50V"
			(at 304.077502 -42.0775 0)
			(layer "F.Fab")
			(hide yes)
			(effects
				(font
					(size 1 1)
					(thickness 0.15)
				)
			)
		)
		(sheetname "FMC+ HSPC")
		(sheetfile "fmc-hspc.kicad_sch")
		(attr smd)
		(fp_rect
			(start -0.925 -0.47)
			(end 0.925 0.47)
			(stroke
				(width 0.05)
				(type default)
			)
			(fill no)
			(layer "F.CrtYd")
		)
		(fp_line
			(start 0.504 -0.25)
			(end 0.504 0.248)
			(stroke
				(width 0.15)
				(type solid)
			)
			(layer "F.Fab")
		)
		(fp_line
			(start -0.494 -0.25)
			(end 0.504 -0.25)
			(stroke
				(width 0.15)
				(type solid)
			)
			(layer "F.Fab")
		)
		(fp_line
			(start 0.504 0.248)
			(end -0.494 0.248)
			(stroke
				(width 0.15)
				(type solid)
			)
			(layer "F.Fab")
		)
		(fp_line
			(start -0.494 0.248)
			(end -0.494 -0.25)
			(stroke
				(width 0.15)
				(type solid)
			)
			(layer "F.Fab")
		)
		(pad "1" smd roundrect
			(at -0.48 0 90)
			(size 0.59 0.64)
			(layers "F.Cu" "F.Mask" "F.Paste")
			(roundrect_rratio 0.25)
			(net 101 "/FMC+ HSPC/GTX115.TX2_N")
			(pintype "passive")
		)
		(pad "2" smd roundrect
			(at 0.48 0 90)
			(size 0.59 0.64)
			(layers "F.Cu" "F.Mask" "F.Paste")
			(roundrect_rratio 0.25)
			(net 98 "/FMC+ HSPC/GTX_TX5_C_N")
			(pintype "passive")
		)
	)
	(footprint "antmicro-footprints:R_0402_1005Metric"
		(layer "F.Cu")
		(at 205.103752 98.9615 90)
		(descr "Resistor SMD 0402")
		(tags "resistor SMD 0402")
		(property "Reference" "R248"
			(at -9.0385 6.596248 90)
			(layer "F.SilkS")
			(effects
				(font
					(size 0.7 0.7)
					(thickness 0.15)
				)
				(justify left bottom)
			)
		)
		(property "Value" "R_12k_0402"
			(at 0 1.4 90)
			(layer "F.Fab")
			(effects
				(font
					(size 0.7 0.7)
					(thickness 0.15)
				)
				(justify left bottom)
			)
		)
		(property "Description" "SMD Chip Resistor, 12 kohm, ± 1%, 62.5 mW, 0402 [1005 Metric], Thick Film, General Purpose"
			(at 0 0 90)
			(layer "F.Fab")
			(hide yes)
			(effects
				(font
					(size 1.27 1.27)
					(thickness 0.15)
				)
			)
		)
		(property "Author" "Antmicro"
			(at 304.065252 -106.142252 0)
			(layer "F.Fab")
			(hide yes)
			(effects
				(font
					(size 1 1)
					(thickness 0.15)
				)
			)
		)
		(property "License" "Apache-2.0"
			(at 304.065252 -106.142252 0)
			(layer "F.Fab")
			(hide yes)
			(effects
				(font
					(size 1 1)
					(thickness 0.15)
				)
			)
		)
		(property "MPN" "CR0402-FX-1202GLF"
			(at 304.065252 -106.142252 0)
			(layer "F.Fab")
			(hide yes)
			(effects
				(font
					(size 1 1)
					(thickness 0.15)
				)
			)
		)
		(property "Manufacturer" "Bourns"
			(at 304.065252 -106.142252 0)
			(layer "F.Fab")
			(hide yes)
			(effects
				(font
					(size 1 1)
					(thickness 0.15)
				)
			)
		)
		(property "Tolerance" "1%"
			(at 304.065252 -106.142252 0)
			(layer "F.Fab")
			(hide yes)
			(effects
				(font
					(size 1 1)
					(thickness 0.15)
				)
			)
		)
		(property "Val" "12k"
			(at 304.065252 -106.142252 0)
			(layer "F.Fab")
			(hide yes)
			(effects
				(font
					(size 1 1)
					(thickness 0.15)
				)
			)
		)
		(sheetname "HDMI + Ethernet")
		(sheetfile "hdmi-ethernet.kicad_sch")
		(attr smd)
		(fp_rect
			(start -0.925 -0.47)
			(end 0.925 0.47)
			(stroke
				(width 0.05)
				(type default)
			)
			(fill no)
			(layer "F.CrtYd")
		)
		(fp_rect
			(start -0.5 -0.25)
			(end 0.5 0.25)
			(stroke
				(width 0.15)
				(type solid)
			)
			(fill no)
			(layer "F.Fab")
		)
		(pad "1" smd roundrect
			(at -0.48 0 90)
			(size 0.59 0.64)
			(layers "F.Cu" "F.Mask" "F.Paste")
			(roundrect_rratio 0.25)
			(net 1 "GND")
			(pintype "passive")
		)
		(pad "2" smd roundrect
			(at 0.48 0 90)
			(size 0.59 0.64)
			(layers "F.Cu" "F.Mask" "F.Paste")
			(roundrect_rratio 0.25)
			(net 953 "/HDMI + Ethernet/GBE_ISET")
			(pintype "passive")
		)
	)
	(footprint "antmicro-footprints:R_0402_1005Metric"
		(layer "F.Cu")
		(at 231.580275 161.75712 -90)
		(descr "Resistor SMD 0402")
		(tags "resistor SMD 0402")
		(property "Reference" "R18"
			(at 0.74288 -0.369725 90)
			(layer "F.SilkS")
			(effects
				(font
					(size 0.7 0.7)
					(thickness 0.15)
				)
				(justify right bottom)
			)
		)
		(property "Value" "R_0R_0402"
			(at 0 1.4 90)
			(layer "F.Fab")
			(effects
				(font
					(size 0.7 0.7)
					(thickness 0.15)
				)
				(justify right bottom)
			)
		)
		(property "Description" "SMD Chip Resistor, Jumper, 0 ohm, 100 mW, 0402 [1005 Metric], Thick Film, General Purpose"
			(at 0 0 270)
			(layer "F.Fab")
			(hide yes)
			(effects
				(font
					(size 1.27 1.27)
					(thickness 0.15)
				)
			)
		)
		(property "Author" "Antmicro"
			(at 69.823155 393.337395 0)
			(layer "F.Fab")
			(hide yes)
			(effects
				(font
					(size 1 1)
					(thickness 0.15)
				)
			)
		)
		(property "Current" "1A"
			(at 69.823155 393.337395 0)
			(layer "F.Fab")
			(hide yes)
			(effects
				(font
					(size 1 1)
					(thickness 0.15)
				)
			)
		)
		(property "License" "Apache-2.0"
			(at 69.823155 393.337395 0)
			(layer "F.Fab")
			(hide yes)
			(effects
				(font
					(size 1 1)
					(thickness 0.15)
				)
			)
		)
		(property "MPN" "ERJ2GE0R00X"
			(at 69.823155 393.337395 0)
			(layer "F.Fab")
			(hide yes)
			(effects
				(font
					(size 1 1)
					(thickness 0.15)
				)
			)
		)
		(property "Manufacturer" "Panasonic"
			(at 69.823155 393.337395 0)
			(layer "F.Fab")
			(hide yes)
			(effects
				(font
					(size 1 1)
					(thickness 0.15)
				)
			)
		)
		(property "Tolerance" ""
			(at 69.823155 393.337395 0)
			(layer "F.Fab")
			(hide yes)
			(effects
				(font
					(size 1 1)
					(thickness 0.15)
				)
			)
		)
		(property "Val" "0R"
			(at 69.823155 393.337395 0)
			(layer "F.Fab")
			(hide yes)
			(effects
				(font
					(size 1 1)
					(thickness 0.15)
				)
			)
		)
		(sheetname "Power supply")
		(sheetfile "power-supply.kicad_sch")
		(attr smd)
		(fp_rect
			(start -0.925 -0.47)
			(end 0.925 0.47)
			(stroke
				(width 0.05)
				(type default)
			)
			(fill no)
			(layer "F.CrtYd")
		)
		(fp_rect
			(start -0.5 -0.25)
			(end 0.5 0.25)
			(stroke
				(width 0.15)
				(type solid)
			)
			(fill no)
			(layer "F.Fab")
		)
		(pad "1" smd roundrect
			(at -0.48 0 270)
			(size 0.59 0.64)
			(layers "F.Cu" "F.Mask" "F.Paste")
			(roundrect_rratio 0.25)
			(net 1349 "/SUP_MCU.PD_RST")
			(pintype "passive")
		)
		(pad "2" smd roundrect
			(at 0.48 0 270)
			(size 0.59 0.64)
			(layers "F.Cu" "F.Mask" "F.Paste")
			(roundrect_rratio 0.25)
			(net 983 "/Power supply/PD_CTRL.RESET")
			(pintype "passive")
		)
	)
	(footprint "antmicro-footprints:R_0402_1005Metric"
		(layer "F.Cu")
		(at 242.599 117.404 -90)
		(descr "Resistor SMD 0402")
		(tags "resistor SMD 0402")
		(property "Reference" "R351"
			(at 1.396 1.649 90)
			(unlocked yes)
			(layer "F.SilkS")
			(effects
				(font
					(size 0.7 0.7)
					(thickness 0.15)
				)
				(justify left bottom)
			)
		)
		(property "Value" "R_2k2_0402"
			(at 0 1.4 270)
			(layer "F.Fab")
			(effects
				(font
					(size 0.7 0.7)
					(thickness 0.15)
				)
				(justify left bottom)
			)
		)
		(property "Description" "SMD Chip Resistor, 2.2 kohm, ± 1%, 62.5 mW, 0402 [1005 Metric], Thick Film, General Purpose"
			(at 0 0 270)
			(layer "F.Fab")
			(hide yes)
			(effects
				(font
					(size 1.27 1.27)
					(thickness 0.15)
				)
			)
		)
		(property "Author" "Antmicro"
			(at 125.195 360.003 0)
			(layer "F.Fab")
			(hide yes)
			(effects
				(font
					(size 1 1)
					(thickness 0.15)
				)
			)
		)
		(property "License" "Apache-2.0"
			(at 125.195 360.003 0)
			(layer "F.Fab")
			(hide yes)
			(effects
				(font
					(size 1 1)
					(thickness 0.15)
				)
			)
		)
		(property "MPN" "CR0402-FX-2201GLF"
			(at 125.195 360.003 0)
			(layer "F.Fab")
			(hide yes)
			(effects
				(font
					(size 1 1)
					(thickness 0.15)
				)
			)
		)
		(property "Manufacturer" "Bourns"
			(at 125.195 360.003 0)
			(layer "F.Fab")
			(hide yes)
			(effects
				(font
					(size 1 1)
					(thickness 0.15)
				)
			)
		)
		(property "Tolerance" "1%"
			(at 125.195 360.003 0)
			(layer "F.Fab")
			(hide yes)
			(effects
				(font
					(size 1 1)
					(thickness 0.15)
				)
			)
		)
		(property "Val" "2k2"
			(at 125.195 360.003 0)
			(layer "F.Fab")
			(hide yes)
			(effects
				(font
					(size 1 1)
					(thickness 0.15)
				)
			)
		)
		(sheetname "USB PHY")
		(sheetfile "usb-phy.kicad_sch")
		(attr smd)
		(fp_rect
			(start -0.925 -0.47)
			(end 0.925 0.47)
			(stroke
				(width 0.05)
				(type default)
			)
			(fill no)
			(layer "F.CrtYd")
		)
		(fp_rect
			(start -0.5 -0.25)
			(end 0.5 0.25)
			(stroke
				(width 0.15)
				(type solid)
			)
			(fill no)
			(layer "F.Fab")
		)
		(pad "1" smd roundrect
			(at -0.48 0 270)
			(size 0.59 0.64)
			(layers "F.Cu" "F.Mask" "F.Paste")
			(roundrect_rratio 0.25)
			(net 389 "Net-(U43-ISET)")
			(pintype "passive")
		)
		(pad "2" smd roundrect
			(at 0.48 0 270)
			(size 0.59 0.64)
			(layers "F.Cu" "F.Mask" "F.Paste")
			(roundrect_rratio 0.25)
			(net 1 "GND")
			(pintype "passive")
		)
	)
	(footprint "antmicro-footprints:NetTie-2_SMD_Pad0.127mm"
		(layer "F.Cu")
		(at 189.1 146.349999)
		(descr "Net tie, 2 pin, 0.127mm  SMD pads")
		(tags "net tie")
		(property "Reference" "NT28"
			(at -0.128 -1.345 0)
			(layer "F.SilkS")
			(hide yes)
			(effects
				(font
					(size 0.7 0.7)
					(thickness 0.15)
				)
				(justify left bottom)
			)
		)
		(property "Value" "Net-Tie_2"
			(at 0 1.199 0)
			(layer "F.Fab")
			(effects
				(font
					(size 0.7 0.7)
					(thickness 0.15)
				)
				(justify left bottom)
			)
		)
		(property "Description" "Net tie, 2 pins"
			(at 0 0 0)
			(layer "F.Fab")
			(hide yes)
			(effects
				(font
					(size 1.27 1.27)
					(thickness 0.15)
				)
			)
		)
		(property "Author" "Antmicro"
			(at 0 0 0)
			(layer "F.Fab")
			(hide yes)
			(effects
				(font
					(size 1 1)
					(thickness 0.15)
				)
			)
		)
		(property "License" "Apache-2.0"
			(at 0 0 0)
			(layer "F.Fab")
			(hide yes)
			(effects
				(font
					(size 1 1)
					(thickness 0.15)
				)
			)
		)
		(property "MPN" ""
			(at 0 0 0)
			(layer "F.Fab")
			(hide yes)
			(effects
				(font
					(size 1 1)
					(thickness 0.15)
				)
			)
		)
		(property "Manufacturer" ""
			(at 0 0 0)
			(layer "F.Fab")
			(hide yes)
			(effects
				(font
					(size 1 1)
					(thickness 0.15)
				)
			)
		)
		(sheetname "DC-DC Converters")
		(sheetfile "dc-dc.kicad_sch")
		(attr exclude_from_pos_files)
		(net_tie_pad_groups "1, 2")
		(fp_poly
			(pts
				(xy -0.0635 -0.0635) (xy 0.0625 -0.0635) (xy 0.0625 0.0635) (xy -0.0635 0.0635)
			)
			(stroke
				(width 0)
				(type solid)
			)
			(fill yes)
			(layer "F.Cu")
		)
		(pad "1" smd roundrect
			(at -0.127 0 180)
			(size 0.127 0.127)
			(layers "F.Cu")
			(roundrect_rratio 0.5)
			(chamfer_ratio 0)
			(chamfer top_left bottom_left)
			(net 1216 "/DC-DC Converters/SENSE_1V35_P")
			(pinfunction "1")
			(pintype "passive")
		)
		(pad "2" smd roundrect
			(at 0.126 0)
			(size 0.127 0.127)
			(layers "F.Cu")
			(roundrect_rratio 0.5)
			(chamfer_ratio 0)
			(chamfer top_left bottom_left)
			(net 25 "+1V35")
			(pinfunction "2")
			(pintype "passive")
		)
	)
	(footprint "antmicro-footprints:Resonator_SMD_Abracon_ABM8G_3.2x2.5mm"
		(layer "F.Cu")
		(at 231.4 139.3)
		(property "Reference" "Y5"
			(at 2.85 0.7 270)
			(layer "F.SilkS")
			(effects
				(font
					(size 0.7 0.7)
					(thickness 0.15)
				)
				(justify left bottom)
			)
		)
		(property "Value" "Resonator_12MHz_ABM8G"
			(at -1.75 2.548 0)
			(layer "F.Fab")
			(effects
				(font
					(size 0.7 0.7)
					(thickness 0.15)
				)
				(justify left bottom)
			)
		)
		(property "Description" "Crystal, 12 MHz, SMT, 3.2mm x 2.5mm, 30 ppm, 18 pF, 20 ppm, ABM8G"
			(at 0 0 0)
			(layer "F.Fab")
			(hide yes)
			(effects
				(font
					(size 1.27 1.27)
					(thickness 0.15)
				)
			)
		)
		(property "Author" "Antmicro"
			(at 0 0 0)
			(layer "F.Fab")
			(hide yes)
			(effects
				(font
					(size 1 1)
					(thickness 0.15)
				)
			)
		)
		(property "License" "Apache-2.0"
			(at 0 0 0)
			(layer "F.Fab")
			(hide yes)
			(effects
				(font
					(size 1 1)
					(thickness 0.15)
				)
			)
		)
		(property "MPN" "ABM8G-12.000MHZ-18-D2Y-T"
			(at 0 0 0)
			(layer "F.Fab")
			(hide yes)
			(effects
				(font
					(size 1 1)
					(thickness 0.15)
				)
			)
		)
		(property "Manufacturer" "Abracon"
			(at 0 0 0)
			(layer "F.Fab")
			(hide yes)
			(effects
				(font
					(size 1 1)
					(thickness 0.15)
				)
			)
		)
		(property "Val" "12 MHz"
			(at 0 0 0)
			(layer "F.Fab")
			(hide yes)
			(effects
				(font
					(size 1 1)
					(thickness 0.15)
				)
			)
		)
		(sheetname "Clocks")
		(sheetfile "clocks.kicad_sch")
		(attr smd)
		(fp_line
			(start -1.6 0.3)
			(end -1.6 -0.2)
			(stroke
				(width 0.15)
				(type solid)
			)
			(layer "F.SilkS")
		)
		(fp_line
			(start -0.35 -1.25)
			(end 0.45 -1.25)
			(stroke
				(width 0.15)
				(type solid)
			)
			(layer "F.SilkS")
		)
		(fp_line
			(start -0.35 1.25)
			(end 0.45 1.25)
			(stroke
				(width 0.15)
				(type solid)
			)
			(layer "F.SilkS")
		)
		(fp_line
			(start 1.6 0.3)
			(end 1.6 -0.2)
			(stroke
				(width 0.15)
				(type solid)
			)
			(layer "F.SilkS")
		)
		(fp_circle
			(center -1.75 1.5)
			(end -1.7 1.5)
			(stroke
				(width 0.15)
				(type solid)
			)
			(fill no)
			(layer "F.SilkS")
		)
		(fp_rect
			(start -1.907 -1.55)
			(end 2.006 1.649)
			(stroke
				(width 0.05)
				(type solid)
			)
			(fill no)
			(layer "F.CrtYd")
		)
		(pad "1" smd roundrect
			(at -1.101 0.949)
			(size 1.3 1.1)
			(layers "F.Cu" "F.Mask" "F.Paste")
			(roundrect_rratio 0)
			(chamfer_ratio 0.2)
			(chamfer bottom_left)
			(net 752 "/Clocks/PLL_XI")
			(pintype "passive")
		)
		(pad "2" smd rect
			(at 1.199 0.949)
			(size 1.3 1.1)
			(layers "F.Cu" "F.Mask" "F.Paste")
			(net 1 "GND")
			(pinfunction "SH")
			(pintype "passive")
		)
		(pad "3" smd rect
			(at 1.199 -0.85)
			(size 1.3 1.1)
			(layers "F.Cu" "F.Mask" "F.Paste")
			(net 753 "/Clocks/PLL_XO")
			(pintype "passive")
		)
		(pad "4" smd rect
			(at -1.101 -0.85)
			(size 1.3 1.1)
			(layers "F.Cu" "F.Mask" "F.Paste")
			(net 1 "GND")
			(pinfunction "SH")
			(pintype "passive")
		)
	)
)
